(kicad_pcb
	(version 20260206)
	(generator "pcbnew")
	(generator_version "10.0")
	(general
		(thickness 1.6)
		(legacy_teardrops no)
	)
	(paper "A4")
	(title_block
		(title "03242023_DA0F0TMBIJ0_F0T_Motherboard_J_brd_V01_OCP.brd")
		(comment 1 "Grand Teton / footprints 2739-2744 of 6105")
	)
	(layers
		(0 "F.Cu" signal "TOP")
		(4 "In1.Cu" signal "GND")
		(6 "In2.Cu" signal "IN1")
		(8 "In3.Cu" signal "GND1")
		(10 "In4.Cu" signal "IN2")
		(12 "In5.Cu" signal "GND2")
		(14 "In6.Cu" signal "IN3")
		(16 "In7.Cu" signal "GND3")
		(18 "In8.Cu" signal "VCC")
		(20 "In9.Cu" signal "VCC1")
		(22 "In10.Cu" signal "GND4")
		(24 "In11.Cu" signal "IN4")
		(26 "In12.Cu" signal "GND5")
		(28 "In13.Cu" signal "IN5")
		(30 "In14.Cu" signal "GND6")
		(32 "In15.Cu" signal "IN6")
		(34 "In16.Cu" signal "GND7")
		(2 "B.Cu" signal "BOTTOM")
		(9 "F.Adhes" user "F.Adhesive")
		(11 "B.Adhes" user "B.Adhesive")
		(13 "F.Paste" user "Package Geometry/Pastemask Top")
		(15 "B.Paste" user "Package Geometry/Pastemask Bottom")
		(5 "F.SilkS" user "Ref Des/Silkscreen Top")
		(7 "B.SilkS" user "Ref Des/Silkscreen Bottom")
		(1 "F.Mask" user "Board Geometry/Soldermask Top")
		(3 "B.Mask" user "Board Geometry/Soldermask Bottom")
		(17 "Dwgs.User" user "User.Drawings")
		(19 "Cmts.User" user "User.Comments")
		(21 "Eco1.User" user "User.Eco1")
		(23 "Eco2.User" user "User.Eco2")
		(25 "Edge.Cuts" user "Board Geometry/Outline")
		(27 "Margin" user)
		(31 "F.CrtYd" user "Package Geometry/Place Bound Top")
		(29 "B.CrtYd" user "Package Geometry/Place Bound Bottom")
		(35 "F.Fab" user "Ref Des/Assembly Top")
		(33 "B.Fab" user "Ref Des/Assembly Bottom")
	)
	(footprint ""
		(layer "F.Cu")
		(at 111.13008 -119.846598 -90)
		(property "Reference" "R851"
			(at 0 0 270)
			(layer "F.SilkS")
			(hide yes)
			(effects
				(font
					(size 1.27 1.27)
				)
			)
		)
		(property "Value" ""
			(at 0 0 270)
			(layer "F.Fab")
			(effects
				(font
					(size 1.27 1.27)
				)
			)
		)
		(duplicate_pad_numbers_are_jumpers no)
		(fp_line
			(start -0.7874 0.4064)
			(end -0.7874 -0.4064)
			(stroke
				(width 0.1524)
				(type default)
			)
			(layer "F.SilkS")
		)
		(fp_line
			(start 0.7874 0.4064)
			(end -0.7874 0.4064)
			(stroke
				(width 0.1524)
				(type default)
			)
			(layer "F.SilkS")
		)
		(fp_line
			(start -0.7874 -0.4064)
			(end 0.7874 -0.4064)
			(stroke
				(width 0.1524)
				(type default)
			)
			(layer "F.SilkS")
		)
		(fp_line
			(start 0.7874 -0.4064)
			(end 0.7874 0.4064)
			(stroke
				(width 0.1524)
				(type default)
			)
			(layer "F.SilkS")
		)
		(fp_line
			(start -0.67945 0.3048)
			(end -0.67945 -0.305054)
			(stroke
				(width 0.1)
				(type default)
			)
			(layer "F.Fab")
		)
		(fp_line
			(start -0.12065 0.3048)
			(end -0.67945 0.3048)
			(stroke
				(width 0.1)
				(type default)
			)
			(layer "F.Fab")
		)
		(fp_line
			(start 0.120396 0.3048)
			(end 0.120396 0.2794)
			(stroke
				(width 0.1)
				(type default)
			)
			(layer "F.Fab")
		)
		(fp_line
			(start 0.67945 0.3048)
			(end 0.120396 0.3048)
			(stroke
				(width 0.1)
				(type default)
			)
			(layer "F.Fab")
		)
		(fp_line
			(start -0.12065 0.2794)
			(end -0.12065 0.3048)
			(stroke
				(width 0.1)
				(type default)
			)
			(layer "F.Fab")
		)
		(fp_line
			(start 0.120396 0.2794)
			(end -0.12065 0.2794)
			(stroke
				(width 0.1)
				(type default)
			)
			(layer "F.Fab")
		)
		(fp_line
			(start -0.12065 -0.2794)
			(end 0.12065 -0.2794)
			(stroke
				(width 0.1)
				(type default)
			)
			(layer "F.Fab")
		)
		(fp_line
			(start 0.12065 -0.2794)
			(end 0.12065 -0.3048)
			(stroke
				(width 0.1)
				(type default)
			)
			(layer "F.Fab")
		)
		(fp_line
			(start 0.12065 -0.3048)
			(end 0.67945 -0.3048)
			(stroke
				(width 0.1)
				(type default)
			)
			(layer "F.Fab")
		)
		(fp_line
			(start 0.67945 -0.3048)
			(end 0.67945 0.3048)
			(stroke
				(width 0.1)
				(type default)
			)
			(layer "F.Fab")
		)
		(fp_line
			(start -0.67945 -0.305054)
			(end -0.12065 -0.305054)
			(stroke
				(width 0.1)
				(type default)
			)
			(layer "F.Fab")
		)
		(fp_line
			(start -0.12065 -0.305054)
			(end -0.12065 -0.2794)
			(stroke
				(width 0.1)
				(type default)
			)
			(layer "F.Fab")
		)
		(pad "1" smd circle
			(at -0.40005 0 270)
			(size 0 0)
			(layers "F.Cu" "F.Mask" "F.Paste")
			(net "RST_CPU0_DRAM_AB_N")
		)
		(pad "2" smd circle
			(at 0.40005 0 270)
			(size 0 0)
			(layers "F.Cu" "F.Mask" "F.Paste")
			(net "RST_CPU0_DRAM_AB_PLD_N")
		)
	)
	(footprint ""
		(layer "F.Cu")
		(at 133.02488 -92.674948 -90)
		(property "Reference" "R4402"
			(at 0 0 270)
			(layer "F.SilkS")
			(hide yes)
			(effects
				(font
					(size 1.27 1.27)
				)
			)
		)
		(property "Value" ""
			(at 0 0 270)
			(layer "F.Fab")
			(effects
				(font
					(size 1.27 1.27)
				)
			)
		)
		(duplicate_pad_numbers_are_jumpers no)
		(fp_line
			(start -0.7874 0.4064)
			(end -0.7874 -0.4064)
			(stroke
				(width 0.1524)
				(type default)
			)
			(layer "F.SilkS")
		)
		(fp_line
			(start 0.7874 0.4064)
			(end -0.7874 0.4064)
			(stroke
				(width 0.1524)
				(type default)
			)
			(layer "F.SilkS")
		)
		(fp_line
			(start -0.7874 -0.4064)
			(end 0.7874 -0.4064)
			(stroke
				(width 0.1524)
				(type default)
			)
			(layer "F.SilkS")
		)
		(fp_line
			(start 0.7874 -0.4064)
			(end 0.7874 0.4064)
			(stroke
				(width 0.1524)
				(type default)
			)
			(layer "F.SilkS")
		)
		(fp_line
			(start -0.67945 0.3048)
			(end -0.67945 -0.305054)
			(stroke
				(width 0.1)
				(type default)
			)
			(layer "F.Fab")
		)
		(fp_line
			(start -0.12065 0.3048)
			(end -0.67945 0.3048)
			(stroke
				(width 0.1)
				(type default)
			)
			(layer "F.Fab")
		)
		(fp_line
			(start 0.120396 0.3048)
			(end 0.120396 0.2794)
			(stroke
				(width 0.1)
				(type default)
			)
			(layer "F.Fab")
		)
		(fp_line
			(start 0.67945 0.3048)
			(end 0.120396 0.3048)
			(stroke
				(width 0.1)
				(type default)
			)
			(layer "F.Fab")
		)
		(fp_line
			(start -0.12065 0.2794)
			(end -0.12065 0.3048)
			(stroke
				(width 0.1)
				(type default)
			)
			(layer "F.Fab")
		)
		(fp_line
			(start 0.120396 0.2794)
			(end -0.12065 0.2794)
			(stroke
				(width 0.1)
				(type default)
			)
			(layer "F.Fab")
		)
		(fp_line
			(start -0.12065 -0.2794)
			(end 0.12065 -0.2794)
			(stroke
				(width 0.1)
				(type default)
			)
			(layer "F.Fab")
		)
		(fp_line
			(start 0.12065 -0.2794)
			(end 0.12065 -0.3048)
			(stroke
				(width 0.1)
				(type default)
			)
			(layer "F.Fab")
		)
		(fp_line
			(start 0.12065 -0.3048)
			(end 0.67945 -0.3048)
			(stroke
				(width 0.1)
				(type default)
			)
			(layer "F.Fab")
		)
		(fp_line
			(start 0.67945 -0.3048)
			(end 0.67945 0.3048)
			(stroke
				(width 0.1)
				(type default)
			)
			(layer "F.Fab")
		)
		(fp_line
			(start -0.67945 -0.305054)
			(end -0.12065 -0.305054)
			(stroke
				(width 0.1)
				(type default)
			)
			(layer "F.Fab")
		)
		(fp_line
			(start -0.12065 -0.305054)
			(end -0.12065 -0.2794)
			(stroke
				(width 0.1)
				(type default)
			)
			(layer "F.Fab")
		)
		(pad "1" smd circle
			(at -0.40005 0 270)
			(size 0 0)
			(layers "F.Cu" "F.Mask" "F.Paste")
			(net "PVNN_TERM_CPU1")
		)
		(pad "2" smd circle
			(at 0.40005 0 270)
			(size 0 0)
			(layers "F.Cu" "F.Mask" "F.Paste")
			(net "H_CPU1_MEMHOT_OUT_LVC1_R_N")
		)
	)
	(footprint ""
		(layer "F.Cu")
		(at 183.515 -93.91015 90)
		(property "Reference" "R4765"
			(at 0 0 90)
			(layer "F.SilkS")
			(hide yes)
			(effects
				(font
					(size 1.27 1.27)
				)
			)
		)
		(property "Value" ""
			(at 0 0 90)
			(layer "F.Fab")
			(effects
				(font
					(size 1.27 1.27)
				)
			)
		)
		(duplicate_pad_numbers_are_jumpers no)
		(fp_line
			(start 0.7874 -0.4064)
			(end 0.7874 0.4064)
			(stroke
				(width 0.1524)
				(type default)
			)
			(layer "F.SilkS")
		)
		(fp_line
			(start -0.7874 -0.4064)
			(end 0.7874 -0.4064)
			(stroke
				(width 0.1524)
				(type default)
			)
			(layer "F.SilkS")
		)
		(fp_line
			(start 0.7874 0.4064)
			(end -0.7874 0.4064)
			(stroke
				(width 0.1524)
				(type default)
			)
			(layer "F.SilkS")
		)
		(fp_line
			(start -0.7874 0.4064)
			(end -0.7874 -0.4064)
			(stroke
				(width 0.1524)
				(type default)
			)
			(layer "F.SilkS")
		)
		(fp_line
			(start -0.12065 -0.305054)
			(end -0.12065 -0.2794)
			(stroke
				(width 0.1)
				(type default)
			)
			(layer "F.Fab")
		)
		(fp_line
			(start -0.67945 -0.305054)
			(end -0.12065 -0.305054)
			(stroke
				(width 0.1)
				(type default)
			)
			(layer "F.Fab")
		)
		(fp_line
			(start 0.67945 -0.3048)
			(end 0.67945 0.3048)
			(stroke
				(width 0.1)
				(type default)
			)
			(layer "F.Fab")
		)
		(fp_line
			(start 0.12065 -0.3048)
			(end 0.67945 -0.3048)
			(stroke
				(width 0.1)
				(type default)
			)
			(layer "F.Fab")
		)
		(fp_line
			(start 0.12065 -0.2794)
			(end 0.12065 -0.3048)
			(stroke
				(width 0.1)
				(type default)
			)
			(layer "F.Fab")
		)
		(fp_line
			(start -0.12065 -0.2794)
			(end 0.12065 -0.2794)
			(stroke
				(width 0.1)
				(type default)
			)
			(layer "F.Fab")
		)
		(fp_line
			(start 0.120396 0.2794)
			(end -0.12065 0.2794)
			(stroke
				(width 0.1)
				(type default)
			)
			(layer "F.Fab")
		)
		(fp_line
			(start -0.12065 0.2794)
			(end -0.12065 0.3048)
			(stroke
				(width 0.1)
				(type default)
			)
			(layer "F.Fab")
		)
		(fp_line
			(start 0.67945 0.3048)
			(end 0.120396 0.3048)
			(stroke
				(width 0.1)
				(type default)
			)
			(layer "F.Fab")
		)
		(fp_line
			(start 0.120396 0.3048)
			(end 0.120396 0.2794)
			(stroke
				(width 0.1)
				(type default)
			)
			(layer "F.Fab")
		)
		(fp_line
			(start -0.12065 0.3048)
			(end -0.67945 0.3048)
			(stroke
				(width 0.1)
				(type default)
			)
			(layer "F.Fab")
		)
		(fp_line
			(start -0.67945 0.3048)
			(end -0.67945 -0.305054)
			(stroke
				(width 0.1)
				(type default)
			)
			(layer "F.Fab")
		)
		(pad "1" smd circle
			(at -0.40005 0 90)
			(size 0 0)
			(layers "F.Cu" "F.Mask" "F.Paste")
			(net "HP_LVC3_E1S_0_HSC_PWRGD")
		)
		(pad "2" smd circle
			(at 0.40005 0 90)
			(size 0 0)
			(layers "F.Cu" "F.Mask" "F.Paste")
			(net "HP_LVC3_E1S_0_HSC_PWRGD_PLD")
		)
	)
	(footprint ""
		(layer "F.Cu")
		(at 424.204892 -386.298948)
		(property "Reference" "R2837"
			(at 0 0 0)
			(layer "F.SilkS")
			(hide yes)
			(effects
				(font
					(size 1.27 1.27)
				)
			)
		)
		(property "Value" ""
			(at 0 0 0)
			(layer "F.Fab")
			(effects
				(font
					(size 1.27 1.27)
				)
			)
		)
		(duplicate_pad_numbers_are_jumpers no)
		(fp_line
			(start -0.7874 -0.4064)
			(end 0.7874 -0.4064)
			(stroke
				(width 0.1524)
				(type default)
			)
			(layer "F.SilkS")
		)
		(fp_line
			(start -0.7874 0.4064)
			(end -0.7874 -0.4064)
			(stroke
				(width 0.1524)
				(type default)
			)
			(layer "F.SilkS")
		)
		(fp_line
			(start 0.7874 -0.4064)
			(end 0.7874 0.4064)
			(stroke
				(width 0.1524)
				(type default)
			)
			(layer "F.SilkS")
		)
		(fp_line
			(start 0.7874 0.4064)
			(end -0.7874 0.4064)
			(stroke
				(width 0.1524)
				(type default)
			)
			(layer "F.SilkS")
		)
		(fp_line
			(start -0.67945 -0.305054)
			(end -0.12065 -0.305054)
			(stroke
				(width 0.1)
				(type default)
			)
			(layer "F.Fab")
		)
		(fp_line
			(start -0.67945 0.3048)
			(end -0.67945 -0.305054)
			(stroke
				(width 0.1)
				(type default)
			)
			(layer "F.Fab")
		)
		(fp_line
			(start -0.12065 -0.305054)
			(end -0.12065 -0.2794)
			(stroke
				(width 0.1)
				(type default)
			)
			(layer "F.Fab")
		)
		(fp_line
			(start -0.12065 -0.2794)
			(end 0.12065 -0.2794)
			(stroke
				(width 0.1)
				(type default)
			)
			(layer "F.Fab")
		)
		(fp_line
			(start -0.12065 0.2794)
			(end -0.12065 0.3048)
			(stroke
				(width 0.1)
				(type default)
			)
			(layer "F.Fab")
		)
		(fp_line
			(start -0.12065 0.3048)
			(end -0.67945 0.3048)
			(stroke
				(width 0.1)
				(type default)
			)
			(layer "F.Fab")
		)
		(fp_line
			(start 0.120396 0.2794)
			(end -0.12065 0.2794)
			(stroke
				(width 0.1)
				(type default)
			)
			(layer "F.Fab")
		)
		(fp_line
			(start 0.120396 0.3048)
			(end 0.120396 0.2794)
			(stroke
				(width 0.1)
				(type default)
			)
			(layer "F.Fab")
		)
		(fp_line
			(start 0.12065 -0.3048)
			(end 0.67945 -0.3048)
			(stroke
				(width 0.1)
				(type default)
			)
			(layer "F.Fab")
		)
		(fp_line
			(start 0.12065 -0.2794)
			(end 0.12065 -0.3048)
			(stroke
				(width 0.1)
				(type default)
			)
			(layer "F.Fab")
		)
		(fp_line
			(start 0.67945 -0.3048)
			(end 0.67945 0.3048)
			(stroke
				(width 0.1)
				(type default)
			)
			(layer "F.Fab")
		)
		(fp_line
			(start 0.67945 0.3048)
			(end 0.120396 0.3048)
			(stroke
				(width 0.1)
				(type default)
			)
			(layer "F.Fab")
		)
		(pad "1" smd circle
			(at -0.40005 0)
			(size 0 0)
			(layers "F.Cu" "F.Mask" "F.Paste")
			(net "P3V3_AUX")
		)
		(pad "2" smd circle
			(at 0.40005 0)
			(size 0 0)
			(layers "F.Cu" "F.Mask" "F.Paste")
			(net "FM_SWB_PWRGD")
		)
	)
	(footprint ""
		(layer "F.Cu")
		(at 178.13782 -353.36353 -90)
		(property "Reference" "PC1244_P1_3"
			(at 0 0 270)
			(layer "F.SilkS")
			(hide yes)
			(effects
				(font
					(size 1.27 1.27)
				)
			)
		)
		(property "Value" ""
			(at 0 0 270)
			(layer "F.Fab")
			(effects
				(font
					(size 1.27 1.27)
				)
			)
		)
		(duplicate_pad_numbers_are_jumpers no)
		(fp_line
			(start -0.7874 0.4064)
			(end -0.7874 -0.4064)
			(stroke
				(width 0.1524)
				(type default)
			)
			(layer "F.SilkS")
		)
		(fp_line
			(start 0.7874 0.4064)
			(end -0.7874 0.4064)
			(stroke
				(width 0.1524)
				(type default)
			)
			(layer "F.SilkS")
		)
		(fp_line
			(start -0.7874 -0.4064)
			(end 0.7874 -0.4064)
			(stroke
				(width 0.1524)
				(type default)
			)
			(layer "F.SilkS")
		)
		(fp_line
			(start 0.7874 -0.4064)
			(end 0.7874 0.4064)
			(stroke
				(width 0.1524)
				(type default)
			)
			(layer "F.SilkS")
		)
		(fp_line
			(start -0.67945 0.3048)
			(end -0.67945 -0.305054)
			(stroke
				(width 0.1)
				(type default)
			)
			(layer "F.Fab")
		)
		(fp_line
			(start -0.12065 0.3048)
			(end -0.67945 0.3048)
			(stroke
				(width 0.1)
				(type default)
			)
			(layer "F.Fab")
		)
		(fp_line
			(start 0.120396 0.3048)
			(end 0.120396 0.2794)
			(stroke
				(width 0.1)
				(type default)
			)
			(layer "F.Fab")
		)
		(fp_line
			(start 0.67945 0.3048)
			(end 0.120396 0.3048)
			(stroke
				(width 0.1)
				(type default)
			)
			(layer "F.Fab")
		)
		(fp_line
			(start -0.12065 0.2794)
			(end -0.12065 0.3048)
			(stroke
				(width 0.1)
				(type default)
			)
			(layer "F.Fab")
		)
		(fp_line
			(start 0.120396 0.2794)
			(end -0.12065 0.2794)
			(stroke
				(width 0.1)
				(type default)
			)
			(layer "F.Fab")
		)
		(fp_line
			(start -0.12065 -0.2794)
			(end 0.12065 -0.2794)
			(stroke
				(width 0.1)
				(type default)
			)
			(layer "F.Fab")
		)
		(fp_line
			(start 0.12065 -0.2794)
			(end 0.12065 -0.3048)
			(stroke
				(width 0.1)
				(type default)
			)
			(layer "F.Fab")
		)
		(fp_line
			(start 0.12065 -0.3048)
			(end 0.67945 -0.3048)
			(stroke
				(width 0.1)
				(type default)
			)
			(layer "F.Fab")
		)
		(fp_line
			(start 0.67945 -0.3048)
			(end 0.67945 0.3048)
			(stroke
				(width 0.1)
				(type default)
			)
			(layer "F.Fab")
		)
		(fp_line
			(start -0.67945 -0.305054)
			(end -0.12065 -0.305054)
			(stroke
				(width 0.1)
				(type default)
			)
			(layer "F.Fab")
		)
		(fp_line
			(start -0.12065 -0.305054)
			(end -0.12065 -0.2794)
			(stroke
				(width 0.1)
				(type default)
			)
			(layer "F.Fab")
		)
		(pad "1" smd circle
			(at -0.40005 0 270)
			(size 0 0)
			(layers "F.Cu" "F.Mask" "F.Paste")
			(net "PVCCFA_EHV_FIVRA_CPU1_PVCC1")
		)
		(pad "2" smd circle
			(at 0.40005 0 270)
			(size 0 0)
			(layers "F.Cu" "F.Mask" "F.Paste")
			(net "GND")
		)
	)
	(footprint ""
		(layer "F.Cu")
		(at 201.00036 -111.724948 180)
		(property "Reference" "R4148"
			(at 0 0 180)
			(layer "F.SilkS")
			(hide yes)
			(effects
				(font
					(size 1.27 1.27)
				)
			)
		)
		(property "Value" ""
			(at 0 0 180)
			(layer "F.Fab")
			(effects
				(font
					(size 1.27 1.27)
				)
			)
		)
		(duplicate_pad_numbers_are_jumpers no)
		(fp_line
			(start 0.7874 0.4064)
			(end -0.7874 0.4064)
			(stroke
				(width 0.1524)
				(type default)
			)
			(layer "F.SilkS")
		)
		(fp_line
			(start 0.7874 -0.4064)
			(end 0.7874 0.4064)
			(stroke
				(width 0.1524)
				(type default)
			)
			(layer "F.SilkS")
		)
		(fp_line
			(start -0.7874 0.4064)
			(end -0.7874 -0.4064)
			(stroke
				(width 0.1524)
				(type default)
			)
			(layer "F.SilkS")
		)
		(fp_line
			(start -0.7874 -0.4064)
			(end 0.7874 -0.4064)
			(stroke
				(width 0.1524)
				(type default)
			)
			(layer "F.SilkS")
		)
		(fp_line
			(start 0.67945 0.3048)
			(end 0.120396 0.3048)
			(stroke
				(width 0.1)
				(type default)
			)
			(layer "F.Fab")
		)
		(fp_line
			(start 0.67945 -0.3048)
			(end 0.67945 0.3048)
			(stroke
				(width 0.1)
				(type default)
			)
			(layer "F.Fab")
		)
		(fp_line
			(start 0.12065 -0.2794)
			(end 0.12065 -0.3048)
			(stroke
				(width 0.1)
				(type default)
			)
			(layer "F.Fab")
		)
		(fp_line
			(start 0.12065 -0.3048)
			(end 0.67945 -0.3048)
			(stroke
				(width 0.1)
				(type default)
			)
			(layer "F.Fab")
		)
		(fp_line
			(start 0.120396 0.3048)
			(end 0.120396 0.2794)
			(stroke
				(width 0.1)
				(type default)
			)
			(layer "F.Fab")
		)
		(fp_line
			(start 0.120396 0.2794)
			(end -0.12065 0.2794)
			(stroke
				(width 0.1)
				(type default)
			)
			(layer "F.Fab")
		)
		(fp_line
			(start -0.12065 0.3048)
			(end -0.67945 0.3048)
			(stroke
				(width 0.1)
				(type default)
			)
			(layer "F.Fab")
		)
		(fp_line
			(start -0.12065 0.2794)
			(end -0.12065 0.3048)
			(stroke
				(width 0.1)
				(type default)
			)
			(layer "F.Fab")
		)
		(fp_line
			(start -0.12065 -0.2794)
			(end 0.12065 -0.2794)
			(stroke
				(width 0.1)
				(type default)
			)
			(layer "F.Fab")
		)
		(fp_line
			(start -0.12065 -0.305054)
			(end -0.12065 -0.2794)
			(stroke
				(width 0.1)
				(type default)
			)
			(layer "F.Fab")
		)
		(fp_line
			(start -0.67945 0.3048)
			(end -0.67945 -0.305054)
			(stroke
				(width 0.1)
				(type default)
			)
			(layer "F.Fab")
		)
		(fp_line
			(start -0.67945 -0.305054)
			(end -0.12065 -0.305054)
			(stroke
				(width 0.1)
				(type default)
			)
			(layer "F.Fab")
		)
		(pad "1" smd circle
			(at -0.40005 0 180)
			(size 0 0)
			(layers "F.Cu" "F.Mask" "F.Paste")
			(net "GPU_3V3IO_RSVD5_FFU_ISO")
		)
		(pad "2" smd circle
			(at 0.40005 0 180)
			(size 0 0)
			(layers "F.Cu" "F.Mask" "F.Paste")
			(net "GPU_3V3IO_RSVD5_FFU_ISO_R")
		)
	)
)
